FILE_TYPE = MULTI_PHYS_TABLE;
PART 'LBG_CORE_QAT_EXT_D'
{====================================================================================================================================================================================================================================================================================================================================================================================================================================================}
:PACK_TYPE  | MATERIAL | PART_NUMBER     = EnvComp        | PART_NUMBER  | JEDEC_TYPE        | DESCRIPTION                                                                                                            | CLASS | COMPONENT_TYPE | HEIGHT     | LPID    | SPEED_URL                                                                                                                | Status |RPL | AML | Bus_Unit | Days ;
{====================================================================================================================================================================================================================================================================================================================================================================================================================================================}
'BGA1'      | 'IC'     | 'H91415-002'(!) = ''             | 'H91415-002' | 'BGA1310_5_LBGA'  | '(USE SYMBOL 1-14) (Physical with OS SM)Lewisburg NS, new Purley PCH, pkg. size 34 x 28mm, pitch 0.65mm'               | 'IC'  | 'BGA'          | '0.102 IN' | '3403'  | 'http://speed.intel.com:8081/speed/module/pdm/item/pdm_item_detail_direct.asp?item_cde=H91415-002&item_rev=01&url_param=unused' | ''     | '' | ''  | ''       | '' 
'BGA1'      | 'EMPTY'  | 'H91415-002'(!) = ''             | 'H91415-002' | 'BGA1310_5_LBGA'  | '(USE SYMBOL 1-14) (Physical with OS SM)Lewisburg NS, new Purley PCH, pkg. size 34 x 28mm, pitch 0.65mm'               | 'IO'  | 'BGA'          | '0.102 IN' | '3403'  | 'http://speed.intel.com:8081/speed/module/pdm/item/pdm_item_detail_direct.asp?item_cde=H91415-002&item_rev=01&url_param=unused' | ''     | '' | ''  | ''       | '' 
'SKT'       | 'IC'     | 'H91415-002'(!) = ''             | 'H91415-002' | 'XBGA1310_5_LBGA' | '(USE SYMBOL 1-14) (Socket Physical with OS SM no PM)Lewisburg NS, new Purley PCH, pkg. size 34 x 28mm, pitch 0.65mm'  | 'IC'  | 'BGA'          | '0.102 IN' | '3403'  | 'http://speed.intel.com:8081/speed/module/pdm/item/pdm_item_detail_direct.asp?item_cde=H91415-002&item_rev=01&url_param=unused' | ''     | '' | ''  | ''       | '' 
'SKT'       | 'EMPTY'  | 'H91415-002'(!) = ''             | 'H91415-002' | 'XBGA1310_5_LBGA' | '(USE SYMBOL 1-14) (Socket Physical with OS SM no PM)Lewisburg NS, new Purley PCH, pkg. size 34 x 28mm, pitch 0.65mm'  | 'IO'  | 'BGA'          | '0.102 IN' | '3403'  | 'http://speed.intel.com:8081/speed/module/pdm/item/pdm_item_detail_direct.asp?item_cde=H91415-002&item_rev=01&url_param=unused' | ''     | '' | ''  | ''       | '' 
END_PART
END.
